(kicad_pcb
	(version 20221018)
	(generator pcbnew)
	(general
    (thickness 1.656)
  )
	(paper "A4")
	(title_block
    (title "SDI-MIPI Bridge")
    (date "2023-08-09")
    (rev "1.3.4")
    (company "Antmicro")
		(comment 9 "footprint 1 of 190 (U2), pads 1-100 of 100")
	)
	(layers
    (0 "F.Cu" signal)
    (1 "In1.Cu" power)
    (2 "In2.Cu" power)
    (3 "In3.Cu" signal)
    (4 "In4.Cu" signal)
    (31 "B.Cu" signal)
    (32 "B.Adhes" user "B.Adhesive")
    (33 "F.Adhes" user "F.Adhesive")
    (34 "B.Paste" user)
    (35 "F.Paste" user)
    (36 "B.SilkS" user "B.Silkscreen")
    (37 "F.SilkS" user "F.Silkscreen")
    (38 "B.Mask" user)
    (39 "F.Mask" user)
    (40 "Dwgs.User" user "User.Drawings")
    (41 "Cmts.User" user "User.Comments")
    (42 "Eco1.User" user "User.Eco1")
    (43 "Eco2.User" user "User.Eco2")
    (44 "Edge.Cuts" user)
    (45 "Margin" user)
    (46 "B.CrtYd" user "B.Courtyard")
    (47 "F.CrtYd" user "F.Courtyard")
    (48 "B.Fab" user)
    (49 "F.Fab" user)
  )
	(footprint "sdi-mipi-bridge-footprints:BGA100_11x11mm_SEMTECH" locked
    (layer "F.Cu")
    (at 121 115.4)
    (property "Author" "Antmicro")
    (property "License" "Apache-2.0")
    (property "MPN" "GS2971A")
    (property "Manufacturer" "Semtech")
    (property "Sheetfile" "sdi-mipi-bridge.kicad_sch")
    (property "Sheetname" "")
    (property "ki_description" "3Gb/s, HD, SD SDI Receiver, with Integrated Adaptive Cable Equalizer complete\nwith SMPTE Audio and Video Processing")
    (attr smd)
    (fp_text reference "U2" (at 0 -6.15) (layer "F.SilkS")
        (effects (font (size 0.7 0.7) (thickness 0.15)) (justify left bottom))
    )
    (fp_text value "GS2971A" (at 0 7) (layer "F.Fab")
        (effects (font (size 0.7 0.7) (thickness 0.15)) (justify left bottom))
    )
    (pad "A1" smd circle locked (at -4.518 -4.494) (size 0.5 0.5) (layers "F.Cu" "F.Paste" "F.Mask")
      (net 11 "/VBG") (pinfunction "VBG") (pintype "input"))
    (pad "A2" smd circle locked (at -3.519 -4.494) (size 0.5 0.5) (layers "F.Cu" "F.Paste" "F.Mask")
      (net 10 "/LF") (pinfunction "LF") (pintype "input"))
    (pad "A3" smd circle locked (at -2.519 -4.494) (size 0.5 0.5) (layers "F.Cu" "F.Paste" "F.Mask")
      (net 40 "/LB_CONT") (pinfunction "LB_CONT") (pintype "input"))
    (pad "A4" smd circle locked (at -1.518 -4.494) (size 0.5 0.5) (layers "F.Cu" "F.Paste" "F.Mask")
      (net 78 "VCO_VDD") (pinfunction "VCO_{VDD}") (pintype "power_in"))
    (pad "A5" smd circle locked (at -0.519 -4.494) (size 0.5 0.5) (layers "F.Cu" "F.Paste" "F.Mask")
      (net 14 "/H_HSYNC") (pinfunction "STAT0") (pintype "output"))
    (pad "A6" smd circle locked (at 0.481 -4.494) (size 0.5 0.5) (layers "F.Cu" "F.Paste" "F.Mask")
      (net 15 "/V_VSYNC") (pinfunction "STAT1") (pintype "output"))
    (pad "A7" smd circle locked (at 1.481 -4.494) (size 0.5 0.5) (layers "F.Cu" "F.Paste" "F.Mask")
      (net 76 "IO_VDD") (pinfunction "IO_{VDD}") (pintype "power_in"))
    (pad "A8" smd circle locked (at 2.482 -4.494) (size 0.5 0.5) (layers "F.Cu" "F.Paste" "F.Mask")
      (net 13 "/PCLK") (pinfunction "PCLK") (pintype "output"))
    (pad "A9" smd circle locked (at 3.482 -4.494) (size 0.5 0.5) (layers "F.Cu" "F.Paste" "F.Mask")
      (net 166 "/DOUT18") (pinfunction "DOUT18") (pintype "output"))
    (pad "A10" smd circle locked (at 4.482 -4.494) (size 0.5 0.5) (layers "F.Cu" "F.Paste" "F.Mask")
      (net 167 "/DOUT17") (pinfunction "DOUT17") (pintype "output"))
    (pad "B1" smd circle locked (at -4.518 -3.493) (size 0.5 0.5) (layers "F.Cu" "F.Paste" "F.Mask")
      (net 5 "+3.3VA") (pinfunction "A_{VDD}") (pintype "power_in"))
    (pad "B2" smd circle locked (at -3.519 -3.493) (size 0.5 0.5) (layers "F.Cu" "F.Paste" "F.Mask")
      (net 4 "VPP") (pinfunction "PLL_{VDD}") (pintype "power_in"))
    (pad "B3" smd circle locked (at -2.519 -3.493) (size 0.5 0.5) (layers "F.Cu" "F.Paste" "F.Mask")
      (net 132 "unconnected-(U2B-RSV-PadB3)") (pinfunction "RSV") (pintype "no_connect"))
    (pad "B4" smd circle locked (at -1.518 -3.493) (size 0.5 0.5) (layers "F.Cu" "F.Paste" "F.Mask")
      (net 3 "GNDA") (pinfunction "VCO_{GND}") (pintype "power_in"))
    (pad "B5" smd circle locked (at -0.519 -3.493) (size 0.5 0.5) (layers "F.Cu" "F.Paste" "F.Mask")
      (net 19 "/F_DE") (pinfunction "STAT2") (pintype "output"))
    (pad "B6" smd circle locked (at 0.481 -3.493) (size 0.5 0.5) (layers "F.Cu" "F.Paste" "F.Mask")
      (net 20 "/LOCKED") (pinfunction "STAT3") (pintype "output"))
    (pad "B7" smd circle locked (at 1.481 -3.493) (size 0.5 0.5) (layers "F.Cu" "F.Paste" "F.Mask")
      (net 1 "GNDREF") (pinfunction "IO_{GND}") (pintype "power_in"))
    (pad "B8" smd circle locked (at 2.482 -3.493) (size 0.5 0.5) (layers "F.Cu" "F.Paste" "F.Mask")
      (net 168 "/DOUT19") (pinfunction "DOUT19") (pintype "output"))
    (pad "B9" smd circle locked (at 3.482 -3.493) (size 0.5 0.5) (layers "F.Cu" "F.Paste" "F.Mask")
      (net 169 "/DOUT16") (pinfunction "DOUT16") (pintype "output"))
    (pad "B10" smd circle locked (at 4.482 -3.493) (size 0.5 0.5) (layers "F.Cu" "F.Paste" "F.Mask")
      (net 170 "/DOUT15") (pinfunction "DOUT15") (pintype "output"))
    (pad "C1" smd circle locked (at -4.518 -2.493) (size 0.5 0.5) (layers "F.Cu" "F.Paste" "F.Mask")
      (net 90 "/SDI_P") (pinfunction "SDI+") (pintype "input"))
    (pad "C2" smd circle locked (at -3.519 -2.493) (size 0.5 0.5) (layers "F.Cu" "F.Paste" "F.Mask")
      (net 3 "GNDA") (pinfunction "A_{GND}") (pintype "power_in"))
    (pad "C3" smd circle locked (at -2.519 -2.493) (size 0.5 0.5) (layers "F.Cu" "F.Paste" "F.Mask")
      (net 4 "VPP") (pinfunction "PLL_{VDD}") (pintype "passive"))
    (pad "C4" smd circle locked (at -1.518 -2.493) (size 0.5 0.5) (layers "F.Cu" "F.Paste" "F.Mask")
      (net 4 "VPP") (pinfunction "PLL_{VDD}") (pintype "passive"))
    (pad "C5" smd circle locked (at -0.519 -2.493) (size 0.5 0.5) (layers "F.Cu" "F.Paste" "F.Mask")
      (net 21 "/Y_1ANC") (pinfunction "STAT4") (pintype "output"))
    (pad "C6" smd circle locked (at 0.481 -2.493) (size 0.5 0.5) (layers "F.Cu" "F.Paste" "F.Mask")
      (net 22 "/~{DATA_ERROR}") (pinfunction "STAT5") (pintype "output"))
    (pad "C7" smd circle locked (at 1.481 -2.493) (size 0.5 0.5) (layers "F.Cu" "F.Paste" "F.Mask")
      (net 126 "/~{RST_TRST}") (pinfunction "RESET_TRST") (pintype "input"))
    (pad "C8" smd circle locked (at 2.482 -2.493) (size 0.5 0.5) (layers "F.Cu" "F.Paste" "F.Mask")
      (net 171 "/DOUT12") (pinfunction "DOUT12") (pintype "output"))
    (pad "C9" smd circle locked (at 3.482 -2.493) (size 0.5 0.5) (layers "F.Cu" "F.Paste" "F.Mask")
      (net 172 "/DOUT14") (pinfunction "DOUT14") (pintype "output"))
    (pad "C10" smd circle locked (at 4.482 -2.493) (size 0.5 0.5) (layers "F.Cu" "F.Paste" "F.Mask")
      (net 173 "/DOUT13") (pinfunction "DOUT13") (pintype "output"))
    (pad "D1" smd circle locked (at -4.518 -1.494) (size 0.5 0.5) (layers "F.Cu" "F.Paste" "F.Mask")
      (net 92 "/SDI_N") (pinfunction "SDI-") (pintype "input"))
    (pad "D2" smd circle locked (at -3.519 -1.494) (size 0.5 0.5) (layers "F.Cu" "F.Paste" "F.Mask")
      (net 3 "GNDA") (pinfunction "A_{GND}") (pintype "passive"))
    (pad "D3" smd circle locked (at -2.519 -1.494) (size 0.5 0.5) (layers "F.Cu" "F.Paste" "F.Mask")
      (net 3 "GNDA") (pinfunction "A_{GND}") (pintype "passive"))
    (pad "D4" smd circle locked (at -1.518 -1.494) (size 0.5 0.5) (layers "F.Cu" "F.Paste" "F.Mask")
      (net 3 "GNDA") (pinfunction "PLL_{GND}") (pintype "power_in"))
    (pad "D5" smd circle locked (at -0.519 -1.494) (size 0.5 0.5) (layers "F.Cu" "F.Paste" "F.Mask")
      (net 1 "GNDREF") (pinfunction "CORE_{GND}") (pintype "power_in"))
    (pad "D6" smd circle locked (at 0.481 -1.494) (size 0.5 0.5) (layers "F.Cu" "F.Paste" "F.Mask")
      (net 2 "+1V2") (pinfunction "CORE_{VDD}") (pintype "power_in"))
    (pad "D7" smd circle locked (at 1.481 -1.494) (size 0.5 0.5) (layers "F.Cu" "F.Paste" "F.Mask")
      (net 47 "/SW_EN") (pinfunction "SW_EN") (pintype "input"))
    (pad "D8" smd circle locked (at 2.482 -1.494) (size 0.5 0.5) (layers "F.Cu" "F.Paste" "F.Mask")
      (net 44 "/JTAG_~{HOST}") (pinfunction "JTAG/~{HOST}") (pintype "input"))
    (pad "D9" smd circle locked (at 3.482 -1.494) (size 0.5 0.5) (layers "F.Cu" "F.Paste" "F.Mask")
      (net 1 "GNDREF") (pinfunction "IO_{GND}") (pintype "passive"))
    (pad "D10" smd circle locked (at 4.482 -1.494) (size 0.5 0.5) (layers "F.Cu" "F.Paste" "F.Mask")
      (net 76 "IO_VDD") (pinfunction "IO_{VDD}") (pintype "passive"))
    (pad "E1" smd circle locked (at -4.518 -0.493) (size 0.5 0.5) (layers "F.Cu" "F.Paste" "F.Mask")
      (net 5 "+3.3VA") (pinfunction "EQ_{VDD}") (pintype "power_in"))
    (pad "E2" smd circle locked (at -3.519 -0.493) (size 0.5 0.5) (layers "F.Cu" "F.Paste" "F.Mask")
      (net 3 "GNDA") (pinfunction "EQ_{GND}") (pintype "power_in"))
    (pad "E3" smd circle locked (at -2.519 -0.493) (size 0.5 0.5) (layers "F.Cu" "F.Paste" "F.Mask")
      (net 3 "GNDA") (pinfunction "A_{GND}") (pintype "passive"))
    (pad "E4" smd circle locked (at -1.518 -0.493) (size 0.5 0.5) (layers "F.Cu" "F.Paste" "F.Mask")
      (net 3 "GNDA") (pinfunction "PLL_{GND}") (pintype "passive"))
    (pad "E5" smd circle locked (at -0.519 -0.493) (size 0.5 0.5) (layers "F.Cu" "F.Paste" "F.Mask")
      (net 1 "GNDREF") (pinfunction "CORE_{GND}") (pintype "passive"))
    (pad "E6" smd circle locked (at 0.481 -0.493) (size 0.5 0.5) (layers "F.Cu" "F.Paste" "F.Mask")
      (net 2 "+1V2") (pinfunction "CORE_{VDD}") (pintype "passive"))
    (pad "E7" smd circle locked (at 1.481 -0.493) (size 0.5 0.5) (layers "F.Cu" "F.Paste" "F.Mask")
      (net 46 "/SDOUT_TDO") (pinfunction "SDOUT_TDO") (pintype "output"))
    (pad "E8" smd circle locked (at 2.482 -0.493) (size 0.5 0.5) (layers "F.Cu" "F.Paste" "F.Mask")
      (net 43 "/SDIN_TDI") (pinfunction "SDIN_TDI") (pintype "input"))
    (pad "E9" smd circle locked (at 3.482 -0.493) (size 0.5 0.5) (layers "F.Cu" "F.Paste" "F.Mask")
      (net 174 "/DOUT10") (pinfunction "DOUT10") (pintype "output"))
    (pad "E10" smd circle locked (at 4.482 -0.493) (size 0.5 0.5) (layers "F.Cu" "F.Paste" "F.Mask")
      (net 175 "/DOUT11") (pinfunction "DOUT11") (pintype "output"))
    (pad "F1" smd circle locked (at -4.518 0.506) (size 0.5 0.5) (layers "F.Cu" "F.Paste" "F.Mask")
      (net 9 "/AGCP") (pinfunction "AGC+") (pintype "passive"))
    (pad "F2" smd circle locked (at -3.519 0.506) (size 0.5 0.5) (layers "F.Cu" "F.Paste" "F.Mask")
      (net 133 "unconnected-(U2B-RSV-PadF2)") (pinfunction "RSV") (pintype "no_connect"))
    (pad "F3" smd circle locked (at -2.519 0.506) (size 0.5 0.5) (layers "F.Cu" "F.Paste" "F.Mask")
      (net 3 "GNDA") (pinfunction "A_{GND}") (pintype "passive"))
    (pad "F4" smd circle locked (at -1.518 0.506) (size 0.5 0.5) (layers "F.Cu" "F.Paste" "F.Mask")
      (net 3 "GNDA") (pinfunction "PLL_{GND}") (pintype "passive"))
    (pad "F5" smd circle locked (at -0.519 0.506) (size 0.5 0.5) (layers "F.Cu" "F.Paste" "F.Mask")
      (net 1 "GNDREF") (pinfunction "CORE_{GND}") (pintype "passive"))
    (pad "F6" smd circle locked (at 0.481 0.506) (size 0.5 0.5) (layers "F.Cu" "F.Paste" "F.Mask")
      (net 2 "+1V2") (pinfunction "CORE_{VDD}") (pintype "passive"))
    (pad "F7" smd circle locked (at 1.481 0.506) (size 0.5 0.5) (layers "F.Cu" "F.Paste" "F.Mask")
      (net 45 "/~{CS}_TMS") (pinfunction "~{CS}_TMS") (pintype "input"))
    (pad "F8" smd circle locked (at 2.482 0.506) (size 0.5 0.5) (layers "F.Cu" "F.Paste" "F.Mask")
      (net 42 "/SCLK_TCK") (pinfunction "SCLK_TCK") (pintype "input"))
    (pad "F9" smd circle locked (at 3.482 0.506) (size 0.5 0.5) (layers "F.Cu" "F.Paste" "F.Mask")
      (net 38 "/D8") (pinfunction "DOUT08") (pintype "output"))
    (pad "F10" smd circle locked (at 4.482 0.506) (size 0.5 0.5) (layers "F.Cu" "F.Paste" "F.Mask")
      (net 39 "/D9") (pinfunction "DOUT09") (pintype "output"))
    (pad "G1" smd circle locked (at -4.518 1.507) (size 0.5 0.5) (layers "F.Cu" "F.Paste" "F.Mask")
      (net 12 "/AGCN") (pinfunction "AGC-") (pintype "passive"))
    (pad "G2" smd circle locked (at -3.519 1.507) (size 0.5 0.5) (layers "F.Cu" "F.Paste" "F.Mask")
      (net 3 "GNDA") (pinfunction "A_{GND}") (pintype "passive"))
    (pad "G3" smd circle locked (at -2.519 1.507) (size 0.5 0.5) (layers "F.Cu" "F.Paste" "F.Mask")
      (net 24 "/~{RC_BYP}") (pinfunction "~{RC_BYP}") (pintype "input"))
    (pad "G4" smd circle locked (at -1.518 1.507) (size 0.5 0.5) (layers "F.Cu" "F.Paste" "F.Mask")
      (net 1 "GNDREF") (pinfunction "CORE_{GND}") (pintype "passive"))
    (pad "G5" smd circle locked (at -0.519 1.507) (size 0.5 0.5) (layers "F.Cu" "F.Paste" "F.Mask")
      (net 1 "GNDREF") (pinfunction "CORE_{GND}") (pintype "passive"))
    (pad "G6" smd circle locked (at 0.481 1.507) (size 0.5 0.5) (layers "F.Cu" "F.Paste" "F.Mask")
      (net 2 "+1V2") (pinfunction "CORE_{VDD}") (pintype "passive"))
    (pad "G7" smd circle locked (at 1.481 1.507) (size 0.5 0.5) (layers "F.Cu" "F.Paste" "F.Mask")
      (net 17 "/~{SMPTE_BYPASS}") (pinfunction "~{SMPTE_BYPASS}") (pintype "bidirectional"))
    (pad "G8" smd circle locked (at 2.482 1.507) (size 0.5 0.5) (layers "F.Cu" "F.Paste" "F.Mask")
      (net 18 "/DVB_ASI") (pinfunction "DVB_ASI") (pintype "bidirectional"))
    (pad "G9" smd circle locked (at 3.482 1.507) (size 0.5 0.5) (layers "F.Cu" "F.Paste" "F.Mask")
      (net 1 "GNDREF") (pinfunction "IO_{GND}") (pintype "passive"))
    (pad "G10" smd circle locked (at 4.482 1.507) (size 0.5 0.5) (layers "F.Cu" "F.Paste" "F.Mask")
      (net 76 "IO_VDD") (pinfunction "IO_{VDD}") (pintype "passive"))
    (pad "H1" smd circle locked (at -4.518 2.507) (size 0.5 0.5) (layers "F.Cu" "F.Paste" "F.Mask")
      (net 5 "+3.3VA") (pinfunction "BUFF_{VDD}") (pintype "power_in"))
    (pad "H2" smd circle locked (at -3.519 2.507) (size 0.5 0.5) (layers "F.Cu" "F.Paste" "F.Mask")
      (net 3 "GNDA") (pinfunction "BUFF_{GND}") (pintype "power_in"))
    (pad "H3" smd circle locked (at -2.519 2.507) (size 0.5 0.5) (layers "F.Cu" "F.Paste" "F.Mask")
      (net 53 "/Audio_EN_~{DIS}") (pinfunction "AUDIO_EN/~{DIS}") (pintype "input"))
    (pad "H4" smd circle locked (at -1.518 2.507) (size 0.5 0.5) (layers "F.Cu" "F.Paste" "F.Mask")
      (net 66 "Net-(U2A-WCLK)") (pinfunction "WCLK") (pintype "output"))
    (pad "H5" smd circle locked (at -0.519 2.507) (size 0.5 0.5) (layers "F.Cu" "F.Paste" "F.Mask")
      (net 23 "/TIM_861") (pinfunction "TIM_861") (pintype "input"))
    (pad "H6" smd circle locked (at 0.481 2.507) (size 0.5 0.5) (layers "F.Cu" "F.Paste" "F.Mask")
      (net 130 "Net-(U2B-XTAL_OUT)") (pinfunction "XTAL_OUT") (pintype "output"))
    (pad "H7" smd circle locked (at 1.481 2.507) (size 0.5 0.5) (layers "F.Cu" "F.Paste" "F.Mask")
      (net 16 "/20bit_~{10bit}") (pinfunction "20BIT/~{10BIT}") (pintype "input"))
    (pad "H8" smd circle locked (at 2.482 2.507) (size 0.5 0.5) (layers "F.Cu" "F.Paste" "F.Mask")
      (net 41 "/IOPROC_EN_~{DIS}") (pinfunction "IOPROC_EN/~{DIS}") (pintype "input"))
    (pad "H9" smd circle locked (at 3.482 2.507) (size 0.5 0.5) (layers "F.Cu" "F.Paste" "F.Mask")
      (net 36 "/D6") (pinfunction "DOUT06") (pintype "output"))
    (pad "H10" smd circle locked (at 4.482 2.507) (size 0.5 0.5) (layers "F.Cu" "F.Paste" "F.Mask")
      (net 37 "/D7") (pinfunction "DOUT07") (pintype "output"))
    (pad "J1" smd circle locked (at -4.518 3.507) (size 0.5 0.5) (layers "F.Cu" "F.Paste" "F.Mask")
      (net 94 "/SDO_P") (pinfunction "SDO+") (pintype "output"))
    (pad "J2" smd circle locked (at -3.519 3.507) (size 0.5 0.5) (layers "F.Cu" "F.Paste" "F.Mask")
      (net 55 "/SDO_EN_DIS") (pinfunction "SDO_EN/DIS") (pintype "input"))
    (pad "J3" smd circle locked (at -2.519 3.507) (size 0.5 0.5) (layers "F.Cu" "F.Paste" "F.Mask")
      (net 52 "/AUDIO_OUTPUT_CH1_2") (pinfunction "AOUT_{1/2}") (pintype "output"))
    (pad "J4" smd circle locked (at -1.518 3.507) (size 0.5 0.5) (layers "F.Cu" "F.Paste" "F.Mask")
      (net 64 "Net-(U2A-ACLK)") (pinfunction "ACLK") (pintype "output"))
    (pad "J5" smd circle locked (at -0.519 3.507) (size 0.5 0.5) (layers "F.Cu" "F.Paste" "F.Mask")
      (net 50 "/AUDIO_OUTPUT_CH5_6") (pinfunction "AOUT_{5/6}") (pintype "output"))
    (pad "J6" smd circle locked (at 0.481 3.507) (size 0.5 0.5) (layers "F.Cu" "F.Paste" "F.Mask")
      (net 7 "/XTAL2") (pinfunction "XTAL2") (pintype "input"))
    (pad "J7" smd circle locked (at 1.481 3.507) (size 0.5 0.5) (layers "F.Cu" "F.Paste" "F.Mask")
      (net 1 "GNDREF") (pinfunction "IO_{GND}") (pintype "passive"))
    (pad "J8" smd circle locked (at 2.482 3.507) (size 0.5 0.5) (layers "F.Cu" "F.Paste" "F.Mask")
      (net 31 "/D1") (pinfunction "DOUT01") (pintype "output"))
    (pad "J9" smd circle locked (at 3.482 3.507) (size 0.5 0.5) (layers "F.Cu" "F.Paste" "F.Mask")
      (net 34 "/D4") (pinfunction "DOUT04") (pintype "output"))
    (pad "J10" smd circle locked (at 4.482 3.507) (size 0.5 0.5) (layers "F.Cu" "F.Paste" "F.Mask")
      (net 35 "/D5") (pinfunction "DOUT05") (pintype "output"))
    (pad "K1" smd circle locked (at -4.518 4.506) (size 0.5 0.5) (layers "F.Cu" "F.Paste" "F.Mask")
      (net 93 "/SDO_N") (pinfunction "SDO-") (pintype "output"))
    (pad "K2" smd circle locked (at -3.519 4.506) (size 0.5 0.5) (layers "F.Cu" "F.Paste" "F.Mask")
      (net 54 "/STANDBY") (pinfunction "STANDBY") (pintype "input"))
    (pad "K3" smd circle locked (at -2.519 4.506) (size 0.5 0.5) (layers "F.Cu" "F.Paste" "F.Mask")
      (net 51 "/AUDIO_OUTPUT_CH3_4") (pinfunction "AOUT_{3/4}") (pintype "output"))
    (pad "K4" smd circle locked (at -1.518 4.506) (size 0.5 0.5) (layers "F.Cu" "F.Paste" "F.Mask")
      (net 63 "Net-(U2A-AMCLK)") (pinfunction "AMCLK") (pintype "output"))
    (pad "K5" smd circle locked (at -0.519 4.506) (size 0.5 0.5) (layers "F.Cu" "F.Paste" "F.Mask")
      (net 49 "/AUDIO_OUTPUT_CH7_8") (pinfunction "AOUT_{7/8}") (pintype "output"))
    (pad "K6" smd circle locked (at 0.481 4.506) (size 0.5 0.5) (layers "F.Cu" "F.Paste" "F.Mask")
      (net 8 "/XTAL1") (pinfunction "XTAL1") (pintype "input"))
    (pad "K7" smd circle locked (at 1.481 4.506) (size 0.5 0.5) (layers "F.Cu" "F.Paste" "F.Mask")
      (net 76 "IO_VDD") (pinfunction "IO_{VDD}") (pintype "passive"))
    (pad "K8" smd circle locked (at 2.482 4.506) (size 0.5 0.5) (layers "F.Cu" "F.Paste" "F.Mask")
      (net 30 "/D0") (pinfunction "DOUT0") (pintype "output"))
    (pad "K9" smd circle locked (at 3.482 4.506) (size 0.5 0.5) (layers "F.Cu" "F.Paste" "F.Mask")
      (net 32 "/D2") (pinfunction "DOUT02") (pintype "output"))
    (pad "K10" smd circle locked (at 4.482 4.506) (size 0.5 0.5) (layers "F.Cu" "F.Paste" "F.Mask")
      (net 33 "/D3") (pinfunction "DOUT03") (pintype "output"))
  )
)
